# T6G (Grand Teton) — schematic netlist excerpt (pin names and nets, part order shuffled) for the footprints in the layout excerpt that follows; sources: Cadence DE-HDL packaged netlist, KiCad conversion of 04192023_DAF0TMB3IC0_F0TG_MB_C_brd_V02_OCP.brd

PC420_4  Q_CAP  22UF 4V 20% X6S  pkg C0805  page 219 : A = PVDDCR_CPU1_P1 ; B = GND
C2320  Q_CAP  22UF 4V 20% X6S  pkg C0402  page 73 : A = PVDDCR_CPU0_P1 ; B = GND
C1889  Q_CAP  0.1UF 25V 10% X7R  pkg 0402  page 233 : A = VFG3P3_CLK_GEN ; B = GND

(kicad_pcb
	(version 20260206)
	(generator "pcbnew")
	(generator_version "10.0")
	(general
		(thickness 1.6)
		(legacy_teardrops no)
	)
	(paper "A4")
	(title_block
		(title "04192023_DAF0TMB3IC0_F0TG_MB_C_brd_V02_OCP.brd")
		(comment 1 "Grand Teton / footprints 5104-5106 of 8354")
	)
	(layers
		(0 "F.Cu" signal "TOP")
		(4 "In1.Cu" signal "GND")
		(6 "In2.Cu" signal "IN1")
		(8 "In3.Cu" signal "GND1")
		(10 "In4.Cu" signal "IN2")
		(12 "In5.Cu" signal "GND2")
		(14 "In6.Cu" signal "IN3")
		(16 "In7.Cu" signal "GND3")
		(18 "In8.Cu" signal "VCC")
		(20 "In9.Cu" signal "VCC1")
		(22 "In10.Cu" signal "GND4")
		(24 "In11.Cu" signal "IN4")
		(26 "In12.Cu" signal "GND5")
		(28 "In13.Cu" signal "IN5")
		(30 "In14.Cu" signal "GND6")
		(32 "In15.Cu" signal "IN6")
		(34 "In16.Cu" signal "GND7")
		(2 "B.Cu" signal "BOTTOM")
		(9 "F.Adhes" user "F.Adhesive")
		(11 "B.Adhes" user "B.Adhesive")
		(13 "F.Paste" user "Package Geometry/Pastemask Top")
		(15 "B.Paste" user "Package Geometry/Pastemask Bottom")
		(5 "F.SilkS" user "Ref Des/Silkscreen Top")
		(7 "B.SilkS" user "Ref Des/Silkscreen Bottom")
		(1 "F.Mask" user "Board Geometry/Soldermask Top")
		(3 "B.Mask" user "Board Geometry/Soldermask Bottom")
		(17 "Dwgs.User" user "User.Drawings")
		(19 "Cmts.User" user "User.Comments")
		(21 "Eco1.User" user "User.Eco1")
		(23 "Eco2.User" user "User.Eco2")
		(25 "Edge.Cuts" user "Board Geometry/Outline")
		(27 "Margin" user)
		(31 "F.CrtYd" user "Package Geometry/Place Bound Top")
		(29 "B.CrtYd" user "Package Geometry/Place Bound Bottom")
		(35 "F.Fab" user "Ref Des/Assembly Top")
		(33 "B.Fab" user "Ref Des/Assembly Bottom")
	)
	(footprint ""
		(layer "B.Cu")
		(at 62.752732 -338.091272 -90)
		(property "Reference" "PC420_4"
			(at 0 0 90)
			(layer "B.SilkS")
			(hide yes)
			(effects
				(font
					(size 1.27 1.27)
				)
				(justify mirror)
			)
		)
		(property "Value" ""
			(at 0 0 90)
			(layer "B.Fab")
			(effects
				(font
					(size 1.27 1.27)
				)
				(justify mirror)
			)
		)
		(duplicate_pad_numbers_are_jumpers no)
		(fp_line
			(start -1.524 0.762)
			(end 1.524 0.762)
			(stroke
				(width 0.1524)
				(type default)
			)
			(layer "B.SilkS")
		)
		(fp_line
			(start 1.524 0.762)
			(end 1.524 -0.762)
			(stroke
				(width 0.1524)
				(type default)
			)
			(layer "B.SilkS")
		)
		(fp_line
			(start -1.524 -0.762)
			(end -1.524 0.762)
			(stroke
				(width 0.1524)
				(type default)
			)
			(layer "B.SilkS")
		)
		(fp_line
			(start 1.524 -0.762)
			(end -1.524 -0.762)
			(stroke
				(width 0.1524)
				(type default)
			)
			(layer "B.SilkS")
		)
		(fp_line
			(start -1.1049 0.724916)
			(end -1.1049 -0.724916)
			(stroke
				(width 0.1)
				(type default)
			)
			(layer "B.Fab")
		)
		(fp_line
			(start 1.1049 0.724916)
			(end -1.1049 0.724916)
			(stroke
				(width 0.1)
				(type default)
			)
			(layer "B.Fab")
		)
		(fp_line
			(start -1.1049 -0.724916)
			(end 1.1049 -0.724916)
			(stroke
				(width 0.1)
				(type default)
			)
			(layer "B.Fab")
		)
		(fp_line
			(start 1.1049 -0.724916)
			(end 1.1049 0.724916)
			(stroke
				(width 0.1)
				(type default)
			)
			(layer "B.Fab")
		)
		(pad "1" smd rect
			(at 0.889 0 270)
			(size 1.016 1.27)
			(layers "B.Cu" "B.Mask" "B.Paste")
			(net "PVDDCR_CPU1_P1")
		)
		(pad "2" smd rect
			(at -0.889 0 270)
			(size 1.016 1.27)
			(layers "B.Cu" "B.Mask" "B.Paste")
			(net "GND")
		)
	)
	(footprint ""
		(layer "B.Cu")
		(at 123.611386 -249.368564)
		(property "Reference" "C2320"
			(at 0 0 0)
			(layer "B.SilkS")
			(hide yes)
			(effects
				(font
					(size 1.27 1.27)
				)
				(justify mirror)
			)
		)
		(property "Value" ""
			(at 0 0 0)
			(layer "B.Fab")
			(effects
				(font
					(size 1.27 1.27)
				)
				(justify mirror)
			)
		)
		(duplicate_pad_numbers_are_jumpers no)
		(fp_line
			(start -0.7874 -0.4064)
			(end -0.7874 0.4064)
			(stroke
				(width 0.1524)
				(type default)
			)
			(layer "B.SilkS")
		)
		(fp_line
			(start -0.7874 0.4064)
			(end 0.7874 0.4064)
			(stroke
				(width 0.1524)
				(type default)
			)
			(layer "B.SilkS")
		)
		(fp_line
			(start 0.7874 -0.4064)
			(end -0.7874 -0.4064)
			(stroke
				(width 0.1524)
				(type default)
			)
			(layer "B.SilkS")
		)
		(fp_line
			(start 0.7874 0.4064)
			(end 0.7874 -0.4064)
			(stroke
				(width 0.1524)
				(type default)
			)
			(layer "B.SilkS")
		)
		(fp_line
			(start -0.67945 -0.3048)
			(end -0.67945 0.3048)
			(stroke
				(width 0.1)
				(type default)
			)
			(layer "B.Fab")
		)
		(fp_line
			(start -0.67945 0.3048)
			(end -0.120396 0.3048)
			(stroke
				(width 0.1)
				(type default)
			)
			(layer "B.Fab")
		)
		(fp_line
			(start -0.12065 -0.3048)
			(end -0.67945 -0.3048)
			(stroke
				(width 0.1)
				(type default)
			)
			(layer "B.Fab")
		)
		(fp_line
			(start -0.12065 -0.2794)
			(end -0.12065 -0.3048)
			(stroke
				(width 0.1)
				(type default)
			)
			(layer "B.Fab")
		)
		(fp_line
			(start -0.120396 0.2794)
			(end 0.12065 0.2794)
			(stroke
				(width 0.1)
				(type default)
			)
			(layer "B.Fab")
		)
		(fp_line
			(start -0.120396 0.3048)
			(end -0.120396 0.2794)
			(stroke
				(width 0.1)
				(type default)
			)
			(layer "B.Fab")
		)
		(fp_line
			(start 0.12065 -0.305054)
			(end 0.12065 -0.2794)
			(stroke
				(width 0.1)
				(type default)
			)
			(layer "B.Fab")
		)
		(fp_line
			(start 0.12065 -0.2794)
			(end -0.12065 -0.2794)
			(stroke
				(width 0.1)
				(type default)
			)
			(layer "B.Fab")
		)
		(fp_line
			(start 0.12065 0.2794)
			(end 0.12065 0.3048)
			(stroke
				(width 0.1)
				(type default)
			)
			(layer "B.Fab")
		)
		(fp_line
			(start 0.12065 0.3048)
			(end 0.67945 0.3048)
			(stroke
				(width 0.1)
				(type default)
			)
			(layer "B.Fab")
		)
		(fp_line
			(start 0.67945 -0.305054)
			(end 0.12065 -0.305054)
			(stroke
				(width 0.1)
				(type default)
			)
			(layer "B.Fab")
		)
		(fp_line
			(start 0.67945 0.3048)
			(end 0.67945 -0.305054)
			(stroke
				(width 0.1)
				(type default)
			)
			(layer "B.Fab")
		)
		(pad "1" smd circle
			(at 0.40005 0 180)
			(size 0 0)
			(layers "B.Cu" "B.Mask" "B.Paste")
			(net "PVDDCR_CPU0_P1")
		)
		(pad "2" smd circle
			(at -0.40005 0 180)
			(size 0 0)
			(layers "B.Cu" "B.Mask" "B.Paste")
			(net "GND")
		)
	)
	(footprint ""
		(layer "B.Cu")
		(at 12.025376 -134.189216 180)
		(property "Reference" "C1889"
			(at 0 0 0)
			(layer "B.SilkS")
			(hide yes)
			(effects
				(font
					(size 1.27 1.27)
				)
				(justify mirror)
			)
		)
		(property "Value" ""
			(at 0 0 0)
			(layer "B.Fab")
			(effects
				(font
					(size 1.27 1.27)
				)
				(justify mirror)
			)
		)
		(duplicate_pad_numbers_are_jumpers no)
		(fp_line
			(start 0.7874 0.4064)
			(end 0.7874 -0.4064)
			(stroke
				(width 0.1524)
				(type default)
			)
			(layer "B.SilkS")
		)
		(fp_line
			(start 0.7874 -0.4064)
			(end -0.7874 -0.4064)
			(stroke
				(width 0.1524)
				(type default)
			)
			(layer "B.SilkS")
		)
		(fp_line
			(start -0.7874 0.4064)
			(end 0.7874 0.4064)
			(stroke
				(width 0.1524)
				(type default)
			)
			(layer "B.SilkS")
		)
		(fp_line
			(start -0.7874 -0.4064)
			(end -0.7874 0.4064)
			(stroke
				(width 0.1524)
				(type default)
			)
			(layer "B.SilkS")
		)
		(fp_line
			(start 0.67945 0.3048)
			(end 0.67945 -0.305054)
			(stroke
				(width 0.1)
				(type default)
			)
			(layer "B.Fab")
		)
		(fp_line
			(start 0.67945 -0.305054)
			(end 0.12065 -0.305054)
			(stroke
				(width 0.1)
				(type default)
			)
			(layer "B.Fab")
		)
		(fp_line
			(start 0.12065 0.3048)
			(end 0.67945 0.3048)
			(stroke
				(width 0.1)
				(type default)
			)
			(layer "B.Fab")
		)
		(fp_line
			(start 0.12065 0.2794)
			(end 0.12065 0.3048)
			(stroke
				(width 0.1)
				(type default)
			)
			(layer "B.Fab")
		)
		(fp_line
			(start 0.12065 -0.2794)
			(end -0.12065 -0.2794)
			(stroke
				(width 0.1)
				(type default)
			)
			(layer "B.Fab")
		)
		(fp_line
			(start 0.12065 -0.305054)
			(end 0.12065 -0.2794)
			(stroke
				(width 0.1)
				(type default)
			)
			(layer "B.Fab")
		)
		(fp_line
			(start -0.120396 0.3048)
			(end -0.120396 0.2794)
			(stroke
				(width 0.1)
				(type default)
			)
			(layer "B.Fab")
		)
		(fp_line
			(start -0.120396 0.2794)
			(end 0.12065 0.2794)
			(stroke
				(width 0.1)
				(type default)
			)
			(layer "B.Fab")
		)
		(fp_line
			(start -0.12065 -0.2794)
			(end -0.12065 -0.3048)
			(stroke
				(width 0.1)
				(type default)
			)
			(layer "B.Fab")
		)
		(fp_line
			(start -0.12065 -0.3048)
			(end -0.67945 -0.3048)
			(stroke
				(width 0.1)
				(type default)
			)
			(layer "B.Fab")
		)
		(fp_line
			(start -0.67945 0.3048)
			(end -0.120396 0.3048)
			(stroke
				(width 0.1)
				(type default)
			)
			(layer "B.Fab")
		)
		(fp_line
			(start -0.67945 -0.3048)
			(end -0.67945 0.3048)
			(stroke
				(width 0.1)
				(type default)
			)
			(layer "B.Fab")
		)
		(pad "1" smd circle
			(at 0.40005 0)
			(size 0 0)
			(layers "B.Cu" "B.Mask" "B.Paste")
			(net "VFG3P3_CLK_GEN")
		)
		(pad "2" smd circle
			(at -0.40005 0)
			(size 0 0)
			(layers "B.Cu" "B.Mask" "B.Paste")
			(net "GND")
		)
	)
)
